# T6G (Grand Teton) — schematic netlist excerpt (pin names and nets, part order shuffled) for the footprints in the layout excerpt that follows; sources: Cadence DE-HDL packaged netlist, KiCad conversion of 04192023_DAF0TMB3IC0_F0TG_MB_C_brd_V02_OCP.brd

C7002  Q_CAP  47UF 4V 20% X6S  pkg C0805  page 279 : A = P0V9_CPU0_RT_2D ; B = GND

U1  M24128BWMN6TP  M24128-BWMN6TP IC  pkg SOIC8XH  page 238
  E0  = CPU_FRU_ADDR0
  E1  = CPU_FRU_ADDR1
  E2  = CPU_FRU_ADDR2
  VSS  = GND
  SDA  = SMB_CPU_FRU_3V3AUX_SDA
  SCL  = SMB_CPU_FRU_3V3AUX_SCL
  \wc#\  = PD_CPU_FRU_WP
  VCC  = P3V3_AUX

R1099  Q_RES  1K 1% EMPTY  pkg 0201LF  page 309 : A = P1V8_CPU0_RT_1D ; B = RT_CPU0_P3_ADDR2

(kicad_pcb
	(version 20260206)
	(generator "pcbnew")
	(generator_version "10.0")
	(general
		(thickness 1.6)
		(legacy_teardrops no)
	)
	(paper "A4")
	(title_block
		(title "04192023_DAF0TMB3IC0_F0TG_MB_C_brd_V02_OCP.brd")
		(comment 1 "Grand Teton / footprints 3236-3238 of 8354")
	)
	(layers
		(0 "F.Cu" signal "TOP")
		(4 "In1.Cu" signal "GND")
		(6 "In2.Cu" signal "IN1")
		(8 "In3.Cu" signal "GND1")
		(10 "In4.Cu" signal "IN2")
		(12 "In5.Cu" signal "GND2")
		(14 "In6.Cu" signal "IN3")
		(16 "In7.Cu" signal "GND3")
		(18 "In8.Cu" signal "VCC")
		(20 "In9.Cu" signal "VCC1")
		(22 "In10.Cu" signal "GND4")
		(24 "In11.Cu" signal "IN4")
		(26 "In12.Cu" signal "GND5")
		(28 "In13.Cu" signal "IN5")
		(30 "In14.Cu" signal "GND6")
		(32 "In15.Cu" signal "IN6")
		(34 "In16.Cu" signal "GND7")
		(2 "B.Cu" signal "BOTTOM")
		(9 "F.Adhes" user "F.Adhesive")
		(11 "B.Adhes" user "B.Adhesive")
		(13 "F.Paste" user "Package Geometry/Pastemask Top")
		(15 "B.Paste" user "Package Geometry/Pastemask Bottom")
		(5 "F.SilkS" user "Ref Des/Silkscreen Top")
		(7 "B.SilkS" user "Ref Des/Silkscreen Bottom")
		(1 "F.Mask" user "Board Geometry/Soldermask Top")
		(3 "B.Mask" user "Board Geometry/Soldermask Bottom")
		(17 "Dwgs.User" user "User.Drawings")
		(19 "Cmts.User" user "User.Comments")
		(21 "Eco1.User" user "User.Eco1")
		(23 "Eco2.User" user "User.Eco2")
		(25 "Edge.Cuts" user "Board Geometry/Outline")
		(27 "Margin" user)
		(31 "F.CrtYd" user "Package Geometry/Place Bound Top")
		(29 "B.CrtYd" user "Package Geometry/Place Bound Bottom")
		(35 "F.Fab" user "Ref Des/Assembly Top")
		(33 "B.Fab" user "Ref Des/Assembly Bottom")
	)
	(footprint ""
		(layer "F.Cu")
		(at 396.258796 -410.144468 90)
		(property "Reference" "C7002"
			(at 0 0 90)
			(layer "F.SilkS")
			(hide yes)
			(effects
				(font
					(size 1.27 1.27)
				)
			)
		)
		(property "Value" ""
			(at 0 0 90)
			(layer "F.Fab")
			(effects
				(font
					(size 1.27 1.27)
				)
			)
		)
		(duplicate_pad_numbers_are_jumpers no)
		(fp_line
			(start 1.524 -0.762)
			(end 1.524 0.762)
			(stroke
				(width 0.1524)
				(type default)
			)
			(layer "F.SilkS")
		)
		(fp_line
			(start -1.524 -0.762)
			(end 1.524 -0.762)
			(stroke
				(width 0.1524)
				(type default)
			)
			(layer "F.SilkS")
		)
		(fp_line
			(start 1.524 0.762)
			(end -1.524 0.762)
			(stroke
				(width 0.1524)
				(type default)
			)
			(layer "F.SilkS")
		)
		(fp_line
			(start -1.524 0.762)
			(end -1.524 -0.762)
			(stroke
				(width 0.1524)
				(type default)
			)
			(layer "F.SilkS")
		)
		(fp_line
			(start 1.1049 -0.724916)
			(end -1.1049 -0.724916)
			(stroke
				(width 0.1)
				(type default)
			)
			(layer "F.Fab")
		)
		(fp_line
			(start -1.1049 -0.724916)
			(end -1.1049 0.724916)
			(stroke
				(width 0.1)
				(type default)
			)
			(layer "F.Fab")
		)
		(fp_line
			(start 1.1049 0.724916)
			(end 1.1049 -0.724916)
			(stroke
				(width 0.1)
				(type default)
			)
			(layer "F.Fab")
		)
		(fp_line
			(start -1.1049 0.724916)
			(end 1.1049 0.724916)
			(stroke
				(width 0.1)
				(type default)
			)
			(layer "F.Fab")
		)
		(pad "1" smd rect
			(at -0.889 0 270)
			(size 1.016 1.27)
			(layers "F.Cu" "F.Mask" "F.Paste")
			(net "P0V9_CPU0_RT_2D")
		)
		(pad "2" smd rect
			(at 0.889 0 270)
			(size 1.016 1.27)
			(layers "F.Cu" "F.Mask" "F.Paste")
			(net "GND")
		)
	)
	(footprint ""
		(layer "F.Cu")
		(at 308.716172 -111.60125)
		(property "Reference" "U1"
			(at -2.1082 -3.165348 0)
			(unlocked yes)
			(layer "F.SilkS")
			(effects
				(font
					(size 0.7874 0.5842)
					(thickness 0.1524)
				)
				(justify left)
			)
		)
		(property "Value" ""
			(at 0 0 0)
			(layer "F.Fab")
			(effects
				(font
					(size 1.27 1.27)
				)
			)
		)
		(duplicate_pad_numbers_are_jumpers no)
		(fp_line
			(start -1.8288 -2.500122)
			(end -1.8288 2.500122)
			(stroke
				(width 0.1524)
				(type default)
			)
			(layer "F.SilkS")
		)
		(fp_line
			(start -1.8288 2.500122)
			(end 1.8288 2.500122)
			(stroke
				(width 0.1524)
				(type default)
			)
			(layer "F.SilkS")
		)
		(fp_line
			(start -1.077722 -2.500122)
			(end -1.8288 -2.500122)
			(stroke
				(width 0.1524)
				(type default)
			)
			(layer "F.SilkS")
		)
		(fp_line
			(start 0 -1.4224)
			(end -1.077722 -2.500122)
			(stroke
				(width 0.1524)
				(type default)
			)
			(layer "F.SilkS")
		)
		(fp_line
			(start 1.077722 -2.500122)
			(end 0 -1.4224)
			(stroke
				(width 0.1524)
				(type default)
			)
			(layer "F.SilkS")
		)
		(fp_line
			(start 1.8288 -2.500122)
			(end 1.077722 -2.500122)
			(stroke
				(width 0.1524)
				(type default)
			)
			(layer "F.SilkS")
		)
		(fp_line
			(start 1.8288 2.500122)
			(end 1.8288 -2.500122)
			(stroke
				(width 0.1524)
				(type default)
			)
			(layer "F.SilkS")
		)
		(fp_poly
			(pts
				(xy -3.59791 -2.765044) (xy -4.675632 -3.1242) (xy -3.95732 -3.842766)
			)
			(stroke
				(width 0)
				(type default)
			)
			(fill yes)
			(layer "F.SilkS")
		)
		(fp_line
			(start -1.999996 -2.500122)
			(end -1.999996 2.500122)
			(stroke
				(width 0.1)
				(type default)
			)
			(layer "F.Fab")
		)
		(fp_line
			(start -1.999996 2.500122)
			(end 1.999996 2.500122)
			(stroke
				(width 0.1)
				(type default)
			)
			(layer "F.Fab")
		)
		(fp_line
			(start 1.999996 -2.500122)
			(end -1.999996 -2.500122)
			(stroke
				(width 0.1)
				(type default)
			)
			(layer "F.Fab")
		)
		(fp_line
			(start 1.999996 2.500122)
			(end 1.999996 -2.500122)
			(stroke
				(width 0.1)
				(type default)
			)
			(layer "F.Fab")
		)
		(fp_poly
			(pts
				(xy -4.5085 -2.413) (xy -4.5085 -1.397) (xy -3.4925 -1.905)
			)
			(stroke
				(width 0)
				(type default)
			)
			(fill yes)
			(layer "F.Fab")
		)
		(pad "1" smd rect
			(at -2.599944 -1.905 270)
			(size 0.889 1.27)
			(layers "F.Cu" "F.Mask" "F.Paste")
			(net "CPU_FRU_ADDR0")
		)
		(pad "2" smd rect
			(at -2.599944 -0.635 270)
			(size 0.889 1.27)
			(layers "F.Cu" "F.Mask" "F.Paste")
			(net "CPU_FRU_ADDR1")
		)
		(pad "3" smd rect
			(at -2.599944 0.635 270)
			(size 0.889 1.27)
			(layers "F.Cu" "F.Mask" "F.Paste")
			(net "CPU_FRU_ADDR2")
		)
		(pad "4" smd rect
			(at -2.599944 1.905 270)
			(size 0.889 1.27)
			(layers "F.Cu" "F.Mask" "F.Paste")
			(net "GND")
		)
		(pad "5" smd rect
			(at 2.599944 1.905 270)
			(size 0.889 1.27)
			(layers "F.Cu" "F.Mask" "F.Paste")
			(net "SMB_CPU_FRU_3V3AUX_SDA")
		)
		(pad "6" smd rect
			(at 2.599944 0.635 270)
			(size 0.889 1.27)
			(layers "F.Cu" "F.Mask" "F.Paste")
			(net "SMB_CPU_FRU_3V3AUX_SCL")
		)
		(pad "7" smd rect
			(at 2.599944 -0.635 270)
			(size 0.889 1.27)
			(layers "F.Cu" "F.Mask" "F.Paste")
			(net "PD_CPU_FRU_WP")
		)
		(pad "8" smd rect
			(at 2.599944 -1.905 270)
			(size 0.889 1.27)
			(layers "F.Cu" "F.Mask" "F.Paste")
			(net "P3V3_AUX")
		)
	)
	(footprint ""
		(layer "F.Cu")
		(at 395.794738 -393.9032 90)
		(property "Reference" "R1099"
			(at 0 0 90)
			(layer "F.SilkS")
			(hide yes)
			(effects
				(font
					(size 1.27 1.27)
				)
			)
		)
		(property "Value" ""
			(at 0 0 90)
			(layer "F.Fab")
			(effects
				(font
					(size 1.27 1.27)
				)
			)
		)
		(duplicate_pad_numbers_are_jumpers no)
		(fp_line
			(start 0.32512 -0.175006)
			(end 0.32512 0.175006)
			(stroke
				(width 0.1)
				(type default)
			)
			(layer "F.Fab")
		)
		(fp_line
			(start -0.32512 -0.175006)
			(end 0.32512 -0.175006)
			(stroke
				(width 0.1)
				(type default)
			)
			(layer "F.Fab")
		)
		(fp_line
			(start 0.32512 0.175006)
			(end -0.32512 0.175006)
			(stroke
				(width 0.1)
				(type default)
			)
			(layer "F.Fab")
		)
		(fp_line
			(start -0.32512 0.175006)
			(end -0.32512 -0.175006)
			(stroke
				(width 0.1)
				(type default)
			)
			(layer "F.Fab")
		)
		(pad "1" smd rect
			(at -0.2667 0 90)
			(size 0.3048 0.381)
			(layers "F.Cu" "F.Mask" "F.Paste")
			(net "P1V8_CPU0_RT_1D")
		)
		(pad "2" smd rect
			(at 0.2667 0 270)
			(size 0.3048 0.381)
			(layers "F.Cu" "F.Mask" "F.Paste")
			(net "RT_CPU0_P3_ADDR2")
		)
	)
)
